#ISCELL
  logical_power cad_note *
  *
#ISCELL
  mstr_misc dns *
  *
#ISCELL
  pure_quanta quanta_title_block_c *
  *
#ISCELL
  logical_power universal_gnd *
  page17_i1
#ISCELL
  logical_power universal_power *
  page17_i100
#CELL
  pure_quanta q_res *
  page17_i101
#ISCELL
  logical_power universal_power *
  page17_i102
#ISCELL
  logical_power universal_gnd *
  page17_i103
#CELL
  pure_quanta q_cap *
  page17_i104
#ISCELL
  logical_power universal_gnd *
  page17_i105
#CELL
  pure_quanta q_cap *
  page17_i106
#CELL
  pure_quanta q_cap *
  page17_i107
#CELL
  pure_quanta q_cap *
  page17_i108
#CELL
  pure_quanta q_cap *
  page17_i109
#CELL
  pure_quanta q_cap *
  page17_i110
#ISCELL
  logical_power universal_power *
  page17_i111
#ISCELL
  standard offpage *
  page17_i112
#ISCELL
  standard offpage *
  page17_i113
#ISCELL
  standard offpage *
  page17_i114
#ISCELL
  standard offpage *
  page17_i115
#CELL
  pure_quanta q_cap *
  page17_i118
#ISCELL
  standard offpage *
  page17_i119
#CELL
  pure_quanta q_inductor *
  page17_i120
#ISCELL
  logical_power universal_power *
  page17_i121
#CELL
  pure_quanta q_cap *
  page17_i122
#ISCELL
  logical_power universal_gnd *
  page17_i123
#CELL
  pure_quanta q_inductor *
  page17_i124
#ISCELL
  logical_power universal_power *
  page17_i125
#CELL
  pure_quanta q_cap *
  page17_i126
#ISCELL
  logical_power universal_gnd *
  page17_i127
#CELL
  pure_quanta q_cap *
  page17_i128
#ISCELL
  standard offpage *
  page17_i129
#ISCELL
  logical_power universal_power *
  page17_i130
#CELL
  pure_quanta q_res *
  page17_i131
#ISCELL
  logical_power universal_power *
  page17_i132
#CELL
  pure_quanta q_cap *
  page17_i133
#ISCELL
  logical_power universal_gnd *
  page17_i134
#CELL
  pure_quanta q_cap *
  page17_i135
#CELL
  pure_quanta q_res *
  page17_i136
#ISCELL
  logical_power universal_power *
  page17_i137
#ISCELL
  standard offpage *
  page17_i138
#CELL
  pure_quanta q_cap *
  page17_i139
#ISCELL
  logical_power universal_gnd *
  page17_i140
#CELL
  pure_quanta q_cap *
  page17_i141
#CELL
  pure_quanta q_inductor *
  page17_i142
#ISCELL
  logical_power universal_power *
  page17_i143
#ISCELL
  standard offpage *
  page17_i144
#CELL
  pure_quanta q_cap *
  page17_i145
#CELL
  pure_quanta q_inductor *
  page17_i146
#ISCELL
  logical_power universal_power *
  page17_i147
#CELL
  pure_quanta q_cap *
  page17_i148
#ISCELL
  logical_power universal_gnd *
  page17_i149
#ISCELL
  standard offpage *
  page17_i150
#CELL
  pure_quanta q_cap *
  page17_i151
#ISCELL
  logical_power universal_gnd *
  page17_i152
#CELL
  pure_quanta q_cap *
  page17_i153
#CELL
  pure_quanta q_inductor *
  page17_i154
#ISCELL
  logical_power universal_power *
  page17_i155
#ISCELL
  standard offpage *
  page17_i156
#CELL
  pure_quanta q_cap *
  page17_i157
#CELL
  pure_quanta q_inductor *
  page17_i158
#ISCELL
  logical_power universal_power *
  page17_i159
#CELL
  pure_quanta q_cap *
  page17_i160
#ISCELL
  logical_power universal_gnd *
  page17_i161
#ISCELL
  standard offpage *
  page17_i162
#CELL
  pure_quanta q_cap *
  page17_i163
#ISCELL
  logical_power universal_gnd *
  page17_i164
#CELL
  pure_quanta q_cap *
  page17_i165
#CELL
  pure_quanta q_inductor *
  page17_i166
#ISCELL
  logical_power universal_power *
  page17_i167
#ISCELL
  standard offpage *
  page17_i168
#CELL
  pure_quanta q_cap *
  page17_i169
#CELL
  pure_quanta q_inductor *
  page17_i170
#ISCELL
  logical_power universal_power *
  page17_i171
#ISCELL
  logical_power universal_gnd *
  page17_i172
#CELL
  pure_quanta q_cap *
  page17_i173
#ISCELL
  logical_power universal_power *
  page17_i174
#CELL
  pure_quanta q_inductor *
  page17_i176
#CELL
  pure_quanta q_cap *
  page17_i178
#ISCELL
  logical_power universal_gnd *
  page17_i179
#CELL
  pure_quanta q_cap *
  page17_i180
#ISCELL
  logical_power universal_gnd *
  page17_i181
#ISCELL
  logical_power universal_gnd *
  page17_i2
#CELL
  pure_quanta mosfet_n_gsd *
  page17_i227
#CELL
  pure_quanta q_res *
  page17_i228
#ISCELL
  standard offpage *
  page17_i229
#CELL
  pure_quanta q_res *
  page17_i230
#ISCELL
  logical_power universal_gnd *
  page17_i232
#ISCELL
  logical_power universal_gnd *
  page17_i233
#CELL
  pure_quanta q_cap *
  page17_i234
#ISCELL
  logical_power universal_power *
  page17_i236
#CELL
  pure_quanta q_cap *
  page17_i239
#ISCELL
  logical_power universal_gnd *
  page17_i240
#ISCELL
  standard offpage *
  page17_i248
#ISCELL
  standard offpage *
  page17_i249
#CELL
  pure_quanta q_cap *
  page17_i250
#ISCELL
  logical_power universal_gnd *
  page17_i251
#CELL
  pure_quanta q_cap *
  page17_i252
#CELL
  pure_quanta q_cap *
  page17_i253
#ISCELL
  logical_power universal_gnd *
  page17_i254
#CELL
  pure_quanta q_cap *
  page17_i255
#CELL
  pure_quanta q_res *
  page17_i256
#CELL
  pure_quanta q_res *
  page17_i259
#CELL
  pure_quanta q_res *
  page17_i260
#ISCELL
  logical_power universal_power *
  page17_i261
#ISCELL
  logical_power universal_power *
  page17_i262
#CELL
  pure_quanta q_res *
  page17_i263
#CELL
  pure_quanta q_res *
  page17_i264
#CELL
  pure_quanta q_res *
  page17_i267
#ISCELL
  logical_power vccaux15 *
  page17_i268
#ISCELL
  logical_power vccaux15 *
  page17_i269
#ISCELL
  logical_power vccaux15 *
  page17_i270
#ISCELL
  logical_power vccaux15 *
  page17_i271
#CELL
  pure_quanta q_inductor *
  page17_i272
#ISCELL
  logical_power vccaux15 *
  page17_i273
#CELL
  pure_quanta mosfet_nch_4d1s *
  page17_i274
#ISCELL
  logical_power universal_power *
  page17_i276
#CELL
  pure_quanta q_res *
  page17_i278
#CELL
  pure_quanta q_res *
  page17_i279
#ISCELL
  logical_power universal_power *
  page17_i283
#CELL
  pure_quanta q_res *
  page17_i284
#ISCELL
  logical_power universal_gnd *
  page17_i285
#CELL
  pure_quanta ast2600a3gp *
  page17_i286
#CELL
  pure_quanta mosfet_pch_gds *
  page17_i289
#ISCELL
  logical_power universal_power *
  page17_i90
#ISCELL
  logical_power universal_power *
  page17_i91
#CELL
  pure_quanta q_res *
  page17_i92
#ISCELL
  logical_power universal_power *
  page17_i93
#CELL
  pure_quanta q_res *
  page17_i94
#CELL
  pure_quanta q_res *
  page17_i95
#ISCELL
  logical_power universal_gnd *
  page17_i96
#CELL
  pure_quanta q_cap *
  page17_i97
#CELL
  pure_quanta q_cap *
  page17_i98
#ISCELL
  logical_power universal_gnd *
  page17_i99
